(kicad_pcb
	(version 20260206)
	(generator "pcbnew")
	(generator_version "10.0")
	(general
		(thickness 1.6)
		(legacy_teardrops no)
	)
	(paper "A4")
	(title_block
		(title "03242023_DA0F0TMBIJ0_F0T_Motherboard_J_brd_V01_OCP.brd")
		(comment 1 "Grand Teton / footprints 2348-2352 of 6105")
	)
	(layers
		(0 "F.Cu" signal "TOP")
		(4 "In1.Cu" signal "GND")
		(6 "In2.Cu" signal "IN1")
		(8 "In3.Cu" signal "GND1")
		(10 "In4.Cu" signal "IN2")
		(12 "In5.Cu" signal "GND2")
		(14 "In6.Cu" signal "IN3")
		(16 "In7.Cu" signal "GND3")
		(18 "In8.Cu" signal "VCC")
		(20 "In9.Cu" signal "VCC1")
		(22 "In10.Cu" signal "GND4")
		(24 "In11.Cu" signal "IN4")
		(26 "In12.Cu" signal "GND5")
		(28 "In13.Cu" signal "IN5")
		(30 "In14.Cu" signal "GND6")
		(32 "In15.Cu" signal "IN6")
		(34 "In16.Cu" signal "GND7")
		(2 "B.Cu" signal "BOTTOM")
		(9 "F.Adhes" user "F.Adhesive")
		(11 "B.Adhes" user "B.Adhesive")
		(13 "F.Paste" user "Package Geometry/Pastemask Top")
		(15 "B.Paste" user "Package Geometry/Pastemask Bottom")
		(5 "F.SilkS" user "Ref Des/Silkscreen Top")
		(7 "B.SilkS" user "Ref Des/Silkscreen Bottom")
		(1 "F.Mask" user "Board Geometry/Soldermask Top")
		(3 "B.Mask" user "Board Geometry/Soldermask Bottom")
		(17 "Dwgs.User" user "User.Drawings")
		(19 "Cmts.User" user "User.Comments")
		(21 "Eco1.User" user "User.Eco1")
		(23 "Eco2.User" user "User.Eco2")
		(25 "Edge.Cuts" user "Board Geometry/Outline")
		(27 "Margin" user)
		(31 "F.CrtYd" user "Package Geometry/Place Bound Top")
		(29 "B.CrtYd" user "Package Geometry/Place Bound Bottom")
		(35 "F.Fab" user "Ref Des/Assembly Top")
		(33 "B.Fab" user "Ref Des/Assembly Bottom")
	)
	(footprint ""
		(layer "F.Cu")
		(at 49.375314 -391.078212 180)
		(property "Reference" "R4644"
			(at 0 0 180)
			(layer "F.SilkS")
			(hide yes)
			(effects
				(font
					(size 1.27 1.27)
				)
			)
		)
		(property "Value" ""
			(at 0 0 180)
			(layer "F.Fab")
			(effects
				(font
					(size 1.27 1.27)
				)
			)
		)
		(duplicate_pad_numbers_are_jumpers no)
		(fp_line
			(start 0.7874 0.4064)
			(end -0.7874 0.4064)
			(stroke
				(width 0.1524)
				(type default)
			)
			(layer "F.SilkS")
		)
		(fp_line
			(start 0.7874 -0.4064)
			(end 0.7874 0.4064)
			(stroke
				(width 0.1524)
				(type default)
			)
			(layer "F.SilkS")
		)
		(fp_line
			(start -0.7874 0.4064)
			(end -0.7874 -0.4064)
			(stroke
				(width 0.1524)
				(type default)
			)
			(layer "F.SilkS")
		)
		(fp_line
			(start -0.7874 -0.4064)
			(end 0.7874 -0.4064)
			(stroke
				(width 0.1524)
				(type default)
			)
			(layer "F.SilkS")
		)
		(fp_line
			(start 0.67945 0.3048)
			(end 0.120396 0.3048)
			(stroke
				(width 0.1)
				(type default)
			)
			(layer "F.Fab")
		)
		(fp_line
			(start 0.67945 -0.3048)
			(end 0.67945 0.3048)
			(stroke
				(width 0.1)
				(type default)
			)
			(layer "F.Fab")
		)
		(fp_line
			(start 0.12065 -0.2794)
			(end 0.12065 -0.3048)
			(stroke
				(width 0.1)
				(type default)
			)
			(layer "F.Fab")
		)
		(fp_line
			(start 0.12065 -0.3048)
			(end 0.67945 -0.3048)
			(stroke
				(width 0.1)
				(type default)
			)
			(layer "F.Fab")
		)
		(fp_line
			(start 0.120396 0.3048)
			(end 0.120396 0.2794)
			(stroke
				(width 0.1)
				(type default)
			)
			(layer "F.Fab")
		)
		(fp_line
			(start 0.120396 0.2794)
			(end -0.12065 0.2794)
			(stroke
				(width 0.1)
				(type default)
			)
			(layer "F.Fab")
		)
		(fp_line
			(start -0.12065 0.3048)
			(end -0.67945 0.3048)
			(stroke
				(width 0.1)
				(type default)
			)
			(layer "F.Fab")
		)
		(fp_line
			(start -0.12065 0.2794)
			(end -0.12065 0.3048)
			(stroke
				(width 0.1)
				(type default)
			)
			(layer "F.Fab")
		)
		(fp_line
			(start -0.12065 -0.2794)
			(end 0.12065 -0.2794)
			(stroke
				(width 0.1)
				(type default)
			)
			(layer "F.Fab")
		)
		(fp_line
			(start -0.12065 -0.305054)
			(end -0.12065 -0.2794)
			(stroke
				(width 0.1)
				(type default)
			)
			(layer "F.Fab")
		)
		(fp_line
			(start -0.67945 0.3048)
			(end -0.67945 -0.305054)
			(stroke
				(width 0.1)
				(type default)
			)
			(layer "F.Fab")
		)
		(fp_line
			(start -0.67945 -0.305054)
			(end -0.12065 -0.305054)
			(stroke
				(width 0.1)
				(type default)
			)
			(layer "F.Fab")
		)
		(pad "1" smd circle
			(at -0.40005 0 180)
			(size 0 0)
			(layers "F.Cu" "F.Mask" "F.Paste")
			(net "P3V3_AUX")
		)
		(pad "2" smd circle
			(at 0.40005 0 180)
			(size 0 0)
			(layers "F.Cu" "F.Mask" "F.Paste")
			(net "FM_P2E_BUF2_EQB1")
		)
	)
	(footprint ""
		(layer "F.Cu")
		(at 213.67496 -360.76382)
		(property "Reference" "H114"
			(at -6.1087 -8.006588 0)
			(unlocked yes)
			(layer "F.SilkS")
			(effects
				(font
					(size 0.7874 0.5842)
					(thickness 0.1524)
				)
				(justify left)
			)
		)
		(property "Value" ""
			(at 0 0 0)
			(layer "F.Fab")
			(effects
				(font
					(size 1.27 1.27)
				)
			)
		)
		(duplicate_pad_numbers_are_jumpers no)
		(fp_circle
			(center 0 0)
			(end 7.999984 0)
			(stroke
				(width 0.1524)
				(type default)
			)
			(fill no)
			(layer "F.SilkS")
		)
		(fp_circle
			(center 0 0)
			(end 7.999984 0)
			(stroke
				(width 0.1524)
				(type default)
			)
			(fill no)
			(layer "B.SilkS")
		)
		(fp_circle
			(center 0 0)
			(end 7.999984 0)
			(stroke
				(width 0.1)
				(type default)
			)
			(fill no)
			(layer "B.Fab")
		)
		(fp_circle
			(center 0 0)
			(end 7.999984 0)
			(stroke
				(width 0.1)
				(type default)
			)
			(fill no)
			(layer "F.Fab")
		)
		(pad "" np_thru_hole circle
			(at 0 0)
			(size 4.0132 4.0132)
			(drill 4.0132)
			(layers "*.Cu" "*.Mask")
			(clearance 0.381)
			(thermal_gap 0.381)
		)
		(pad "2" thru_hole circle
			(at 3.2639 0)
			(size 0.9144 0.9144)
			(drill 0.5588)
			(layers "*.Cu" "*.Mask")
			(remove_unused_layers no)
			(net "GND")
			(clearance 0.0762)
			(thermal_gap 0.0762)
		)
		(pad "3" thru_hole circle
			(at 2.307844 -2.307844)
			(size 0.9144 0.9144)
			(drill 0.5588)
			(layers "*.Cu" "*.Mask")
			(remove_unused_layers no)
			(net "GND")
			(clearance 0.0762)
			(thermal_gap 0.0762)
		)
		(pad "4" thru_hole circle
			(at 0 -3.2639)
			(size 0.9144 0.9144)
			(drill 0.5588)
			(layers "*.Cu" "*.Mask")
			(remove_unused_layers no)
			(net "GND")
			(clearance 0.0762)
			(thermal_gap 0.0762)
		)
		(pad "5" thru_hole circle
			(at -2.307844 -2.307844)
			(size 0.9144 0.9144)
			(drill 0.5588)
			(layers "*.Cu" "*.Mask")
			(remove_unused_layers no)
			(net "GND")
			(clearance 0.0762)
			(thermal_gap 0.0762)
		)
		(pad "6" thru_hole circle
			(at -3.2639 0)
			(size 0.9144 0.9144)
			(drill 0.5588)
			(layers "*.Cu" "*.Mask")
			(remove_unused_layers no)
			(net "GND")
			(clearance 0.0762)
			(thermal_gap 0.0762)
		)
		(pad "7" thru_hole circle
			(at -2.307844 2.307844)
			(size 0.9144 0.9144)
			(drill 0.5588)
			(layers "*.Cu" "*.Mask")
			(remove_unused_layers no)
			(net "GND")
			(clearance 0.0762)
			(thermal_gap 0.0762)
		)
		(pad "8" thru_hole circle
			(at 0 3.2639)
			(size 0.9144 0.9144)
			(drill 0.5588)
			(layers "*.Cu" "*.Mask")
			(remove_unused_layers no)
			(net "GND")
			(clearance 0.0762)
			(thermal_gap 0.0762)
		)
		(pad "9" thru_hole circle
			(at 2.307844 2.307844)
			(size 0.9144 0.9144)
			(drill 0.5588)
			(layers "*.Cu" "*.Mask")
			(remove_unused_layers no)
			(net "GND")
			(clearance 0.0762)
			(thermal_gap 0.0762)
		)
		(zone
			(layer "F.Cu")
			(hatch none 0.5)
			(connect_pads
				(clearance 0)
			)
			(min_thickness 0.25)
			(keepout
				(tracks not_allowed)
				(vias allowed)
				(pads allowed)
				(copperpour not_allowed)
				(footprints allowed)
			)
			(placement
				(enabled no)
				(sheetname "")
			)
			(fill
				(thermal_gap 0.5)
				(thermal_bridge_width 0.5)
				(island_removal_mode 0)
			)
			(polygon
				(pts
					(arc
						(start 213.67496 -356.49662)
						(mid 209.40776 -360.76382)
						(end 213.67496 -365.03102)
					)
					(arc
						(start 213.67496 -368.763804)
						(mid 208.018117 -366.420663)
						(end 205.674976 -360.76382)
					)
					(arc
						(start 205.674976 -360.76382)
						(mid 208.018117 -355.106977)
						(end 213.67496 -352.763836)
					)
				)
			)
		)
		(zone
			(layer "F.Cu")
			(hatch none 0.5)
			(connect_pads
				(clearance 0)
			)
			(min_thickness 0.25)
			(keepout
				(tracks not_allowed)
				(vias allowed)
				(pads allowed)
				(copperpour not_allowed)
				(footprints allowed)
			)
			(placement
				(enabled no)
				(sheetname "")
			)
			(fill
				(thermal_gap 0.5)
				(thermal_bridge_width 0.5)
				(island_removal_mode 0)
			)
			(polygon
				(pts
					(arc
						(start 213.67496 -356.49662)
						(mid 217.94216 -360.76382)
						(end 213.67496 -365.03102)
					)
					(arc
						(start 213.67496 -368.763804)
						(mid 219.331803 -366.420663)
						(end 221.674944 -360.76382)
					)
					(arc
						(start 221.674944 -360.76382)
						(mid 219.331803 -355.106977)
						(end 213.67496 -352.763836)
					)
				)
			)
		)
		(zone
			(layers "F.Cu" "B.Cu" "In1.Cu" "In2.Cu" "In3.Cu" "In4.Cu" "In5.Cu" "In6.Cu"
				"In7.Cu" "In8.Cu" "In9.Cu" "In10.Cu" "In11.Cu" "In12.Cu" "In13.Cu" "In14.Cu"
				"In15.Cu" "In16.Cu"
			)
			(hatch none 0.5)
			(connect_pads
				(clearance 0)
			)
			(min_thickness 0.25)
			(keepout
				(tracks not_allowed)
				(vias allowed)
				(pads allowed)
				(copperpour not_allowed)
				(footprints allowed)
			)
			(placement
				(enabled no)
				(sheetname "")
			)
			(fill
				(thermal_gap 0.5)
				(thermal_bridge_width 0.5)
				(island_removal_mode 0)
			)
			(polygon
				(pts
					(arc
						(start 216.18702 -360.76382)
						(mid 211.1629 -360.76382)
						(end 216.18702 -360.76382)
					)
				)
			)
		)
		(zone
			(layer "B.Cu")
			(hatch none 0.5)
			(connect_pads
				(clearance 0)
			)
			(min_thickness 0.25)
			(keepout
				(tracks not_allowed)
				(vias allowed)
				(pads allowed)
				(copperpour not_allowed)
				(footprints allowed)
			)
			(placement
				(enabled no)
				(sheetname "")
			)
			(fill
				(thermal_gap 0.5)
				(thermal_bridge_width 0.5)
				(island_removal_mode 0)
			)
			(polygon
				(pts
					(arc
						(start 213.67496 -365.28502)
						(mid 209.15376 -360.76382)
						(end 213.67496 -356.24262)
					)
					(arc
						(start 213.67496 -356.72522)
						(mid 209.63636 -360.76382)
						(end 213.67496 -364.80242)
					)
				)
			)
		)
		(zone
			(layer "B.Cu")
			(hatch none 0.5)
			(connect_pads
				(clearance 0)
			)
			(min_thickness 0.25)
			(keepout
				(tracks not_allowed)
				(vias allowed)
				(pads allowed)
				(copperpour not_allowed)
				(footprints allowed)
			)
			(placement
				(enabled no)
				(sheetname "")
			)
			(fill
				(thermal_gap 0.5)
				(thermal_bridge_width 0.5)
				(island_removal_mode 0)
			)
			(polygon
				(pts
					(arc
						(start 213.67496 -365.28502)
						(mid 218.19616 -360.76382)
						(end 213.67496 -356.24262)
					)
					(arc
						(start 213.67496 -356.72522)
						(mid 217.71356 -360.76382)
						(end 213.67496 -364.80242)
					)
				)
			)
		)
	)
	(footprint ""
		(layer "F.Cu")
		(at 145.549874 -402.371052 -90)
		(property "Reference" "C758"
			(at 0 0 270)
			(layer "F.SilkS")
			(hide yes)
			(effects
				(font
					(size 1.27 1.27)
				)
			)
		)
		(property "Value" ""
			(at 0 0 270)
			(layer "F.Fab")
			(effects
				(font
					(size 1.27 1.27)
				)
			)
		)
		(duplicate_pad_numbers_are_jumpers no)
		(fp_line
			(start -0.299974 0.150114)
			(end -0.299974 -0.150114)
			(stroke
				(width 0.1)
				(type default)
			)
			(layer "F.Fab")
		)
		(fp_line
			(start 0.299974 0.150114)
			(end -0.299974 0.150114)
			(stroke
				(width 0.1)
				(type default)
			)
			(layer "F.Fab")
		)
		(fp_line
			(start -0.299974 -0.150114)
			(end 0.299974 -0.150114)
			(stroke
				(width 0.1)
				(type default)
			)
			(layer "F.Fab")
		)
		(fp_line
			(start 0.299974 -0.150114)
			(end 0.299974 0.150114)
			(stroke
				(width 0.1)
				(type default)
			)
			(layer "F.Fab")
		)
		(pad "1" smd rect
			(at -0.2667 0 270)
			(size 0.3048 0.381)
			(layers "F.Cu" "F.Mask" "F.Paste")
			(net "P5E_CPU1_PE2_TX_C_DN<7>")
		)
		(pad "2" smd rect
			(at 0.2667 0 270)
			(size 0.3048 0.381)
			(layers "F.Cu" "F.Mask" "F.Paste")
			(net "P5E_CPU1_PE2_TX_DN<7>")
		)
	)
	(footprint ""
		(layer "F.Cu")
		(at 80.32115 -151.383492 180)
		(property "Reference" "R668"
			(at 0 0 180)
			(layer "F.SilkS")
			(hide yes)
			(effects
				(font
					(size 1.27 1.27)
				)
			)
		)
		(property "Value" ""
			(at 0 0 180)
			(layer "F.Fab")
			(effects
				(font
					(size 1.27 1.27)
				)
			)
		)
		(duplicate_pad_numbers_are_jumpers no)
		(fp_line
			(start 0.7874 0.4064)
			(end -0.7874 0.4064)
			(stroke
				(width 0.1524)
				(type default)
			)
			(layer "F.SilkS")
		)
		(fp_line
			(start 0.7874 -0.4064)
			(end 0.7874 0.4064)
			(stroke
				(width 0.1524)
				(type default)
			)
			(layer "F.SilkS")
		)
		(fp_line
			(start -0.7874 0.4064)
			(end -0.7874 -0.4064)
			(stroke
				(width 0.1524)
				(type default)
			)
			(layer "F.SilkS")
		)
		(fp_line
			(start -0.7874 -0.4064)
			(end 0.7874 -0.4064)
			(stroke
				(width 0.1524)
				(type default)
			)
			(layer "F.SilkS")
		)
		(fp_line
			(start 0.67945 0.3048)
			(end 0.120396 0.3048)
			(stroke
				(width 0.1)
				(type default)
			)
			(layer "F.Fab")
		)
		(fp_line
			(start 0.67945 -0.3048)
			(end 0.67945 0.3048)
			(stroke
				(width 0.1)
				(type default)
			)
			(layer "F.Fab")
		)
		(fp_line
			(start 0.12065 -0.2794)
			(end 0.12065 -0.3048)
			(stroke
				(width 0.1)
				(type default)
			)
			(layer "F.Fab")
		)
		(fp_line
			(start 0.12065 -0.3048)
			(end 0.67945 -0.3048)
			(stroke
				(width 0.1)
				(type default)
			)
			(layer "F.Fab")
		)
		(fp_line
			(start 0.120396 0.3048)
			(end 0.120396 0.2794)
			(stroke
				(width 0.1)
				(type default)
			)
			(layer "F.Fab")
		)
		(fp_line
			(start 0.120396 0.2794)
			(end -0.12065 0.2794)
			(stroke
				(width 0.1)
				(type default)
			)
			(layer "F.Fab")
		)
		(fp_line
			(start -0.12065 0.3048)
			(end -0.67945 0.3048)
			(stroke
				(width 0.1)
				(type default)
			)
			(layer "F.Fab")
		)
		(fp_line
			(start -0.12065 0.2794)
			(end -0.12065 0.3048)
			(stroke
				(width 0.1)
				(type default)
			)
			(layer "F.Fab")
		)
		(fp_line
			(start -0.12065 -0.2794)
			(end 0.12065 -0.2794)
			(stroke
				(width 0.1)
				(type default)
			)
			(layer "F.Fab")
		)
		(fp_line
			(start -0.12065 -0.305054)
			(end -0.12065 -0.2794)
			(stroke
				(width 0.1)
				(type default)
			)
			(layer "F.Fab")
		)
		(fp_line
			(start -0.67945 0.3048)
			(end -0.67945 -0.305054)
			(stroke
				(width 0.1)
				(type default)
			)
			(layer "F.Fab")
		)
		(fp_line
			(start -0.67945 -0.305054)
			(end -0.12065 -0.305054)
			(stroke
				(width 0.1)
				(type default)
			)
			(layer "F.Fab")
		)
		(pad "1" smd circle
			(at -0.40005 0 180)
			(size 0 0)
			(layers "F.Cu" "F.Mask" "F.Paste")
			(net "I3C_SPD_DDREFGH_CPU1_R_SDA")
		)
		(pad "2" smd circle
			(at 0.40005 0 180)
			(size 0 0)
			(layers "F.Cu" "F.Mask" "F.Paste")
			(net "I3C_SPD_DDREFGH_CPU1_LVC1_R_SDA")
		)
	)
	(footprint ""
		(layer "F.Cu")
		(at 66.369438 -31.887922 90)
		(property "Reference" "PC2166"
			(at 0 0 90)
			(layer "F.SilkS")
			(hide yes)
			(effects
				(font
					(size 1.27 1.27)
				)
			)
		)
		(property "Value" ""
			(at 0 0 90)
			(layer "F.Fab")
			(effects
				(font
					(size 1.27 1.27)
				)
			)
		)
		(duplicate_pad_numbers_are_jumpers no)
		(fp_line
			(start 0.7874 -0.4064)
			(end 0.7874 0.4064)
			(stroke
				(width 0.1524)
				(type default)
			)
			(layer "F.SilkS")
		)
		(fp_line
			(start -0.7874 -0.4064)
			(end 0.7874 -0.4064)
			(stroke
				(width 0.1524)
				(type default)
			)
			(layer "F.SilkS")
		)
		(fp_line
			(start 0.7874 0.4064)
			(end -0.7874 0.4064)
			(stroke
				(width 0.1524)
				(type default)
			)
			(layer "F.SilkS")
		)
		(fp_line
			(start -0.7874 0.4064)
			(end -0.7874 -0.4064)
			(stroke
				(width 0.1524)
				(type default)
			)
			(layer "F.SilkS")
		)
		(fp_line
			(start -0.12065 -0.305054)
			(end -0.12065 -0.2794)
			(stroke
				(width 0.1)
				(type default)
			)
			(layer "F.Fab")
		)
		(fp_line
			(start -0.67945 -0.305054)
			(end -0.12065 -0.305054)
			(stroke
				(width 0.1)
				(type default)
			)
			(layer "F.Fab")
		)
		(fp_line
			(start 0.67945 -0.3048)
			(end 0.67945 0.3048)
			(stroke
				(width 0.1)
				(type default)
			)
			(layer "F.Fab")
		)
		(fp_line
			(start 0.12065 -0.3048)
			(end 0.67945 -0.3048)
			(stroke
				(width 0.1)
				(type default)
			)
			(layer "F.Fab")
		)
		(fp_line
			(start 0.12065 -0.2794)
			(end 0.12065 -0.3048)
			(stroke
				(width 0.1)
				(type default)
			)
			(layer "F.Fab")
		)
		(fp_line
			(start -0.12065 -0.2794)
			(end 0.12065 -0.2794)
			(stroke
				(width 0.1)
				(type default)
			)
			(layer "F.Fab")
		)
		(fp_line
			(start 0.120396 0.2794)
			(end -0.12065 0.2794)
			(stroke
				(width 0.1)
				(type default)
			)
			(layer "F.Fab")
		)
		(fp_line
			(start -0.12065 0.2794)
			(end -0.12065 0.3048)
			(stroke
				(width 0.1)
				(type default)
			)
			(layer "F.Fab")
		)
		(fp_line
			(start 0.67945 0.3048)
			(end 0.120396 0.3048)
			(stroke
				(width 0.1)
				(type default)
			)
			(layer "F.Fab")
		)
		(fp_line
			(start 0.120396 0.3048)
			(end 0.120396 0.2794)
			(stroke
				(width 0.1)
				(type default)
			)
			(layer "F.Fab")
		)
		(fp_line
			(start -0.12065 0.3048)
			(end -0.67945 0.3048)
			(stroke
				(width 0.1)
				(type default)
			)
			(layer "F.Fab")
		)
		(fp_line
			(start -0.67945 0.3048)
			(end -0.67945 -0.305054)
			(stroke
				(width 0.1)
				(type default)
			)
			(layer "F.Fab")
		)
		(pad "1" smd circle
			(at -0.40005 0 90)
			(size 0 0)
			(layers "F.Cu" "F.Mask" "F.Paste")
			(net "P12V_OCP_SS_2")
		)
		(pad "2" smd circle
			(at 0.40005 0 90)
			(size 0 0)
			(layers "F.Cu" "F.Mask" "F.Paste")
			(net "GND")
		)
	)
)
